(kicad_pcb
	(version 20260206)
	(generator "pcbnew")
	(generator_version "10.0")
	(general
		(thickness 1.6)
		(legacy_teardrops no)
	)
	(paper "A4")
	(title_block
		(title "12092022_DA0F0TMDCD0_F0T_Management_Board_D_brd_V3_OCP.brd")
		(comment 1 "Grand Teton / footprints 569-574 of 1440")
	)
	(layers
		(0 "F.Cu" signal "TOP")
		(4 "In1.Cu" signal "GND")
		(6 "In2.Cu" signal "IN1")
		(8 "In3.Cu" signal "GND1")
		(10 "In4.Cu" signal "IN2")
		(12 "In5.Cu" signal "VCC")
		(14 "In6.Cu" signal "VCC1")
		(16 "In7.Cu" signal "IN3")
		(18 "In8.Cu" signal "GND2")
		(20 "In9.Cu" signal "IN4")
		(22 "In10.Cu" signal "GND3")
		(2 "B.Cu" signal "BOTTOM")
		(9 "F.Adhes" user "F.Adhesive")
		(11 "B.Adhes" user "B.Adhesive")
		(13 "F.Paste" user "Package Geometry/Pastemask Top")
		(15 "B.Paste" user "Package Geometry/Pastemask Bottom")
		(5 "F.SilkS" user "Ref Des/Silkscreen Top")
		(7 "B.SilkS" user "Ref Des/Silkscreen Bottom")
		(1 "F.Mask" user "Board Geometry/Soldermask Top")
		(3 "B.Mask" user "Board Geometry/Soldermask Bottom")
		(17 "Dwgs.User" user "User.Drawings")
		(19 "Cmts.User" user "User.Comments")
		(21 "Eco1.User" user "User.Eco1")
		(23 "Eco2.User" user "User.Eco2")
		(25 "Edge.Cuts" user "Board Geometry/Outline")
		(27 "Margin" user)
		(31 "F.CrtYd" user "Package Geometry/Place Bound Top")
		(29 "B.CrtYd" user "Package Geometry/Place Bound Bottom")
		(35 "F.Fab" user "Ref Des/Assembly Top")
		(33 "B.Fab" user "Ref Des/Assembly Bottom")
	)
	(footprint ""
		(layer "F.Cu")
		(at 59.7154 -64.0588 90)
		(property "Reference" "R724"
			(at 0 0 90)
			(layer "F.SilkS")
			(hide yes)
			(effects
				(font
					(size 1.27 1.27)
				)
			)
		)
		(property "Value" ""
			(at 0 0 90)
			(layer "F.Fab")
			(effects
				(font
					(size 1.27 1.27)
				)
			)
		)
		(duplicate_pad_numbers_are_jumpers no)
		(fp_line
			(start 0.7874 -0.4064)
			(end 0.7874 0.4064)
			(stroke
				(width 0.1524)
				(type default)
			)
			(layer "F.SilkS")
		)
		(fp_line
			(start -0.7874 -0.4064)
			(end 0.7874 -0.4064)
			(stroke
				(width 0.1524)
				(type default)
			)
			(layer "F.SilkS")
		)
		(fp_line
			(start 0.7874 0.4064)
			(end -0.7874 0.4064)
			(stroke
				(width 0.1524)
				(type default)
			)
			(layer "F.SilkS")
		)
		(fp_line
			(start -0.7874 0.4064)
			(end -0.7874 -0.4064)
			(stroke
				(width 0.1524)
				(type default)
			)
			(layer "F.SilkS")
		)
		(fp_line
			(start -0.12065 -0.305054)
			(end -0.12065 -0.2794)
			(stroke
				(width 0.1)
				(type default)
			)
			(layer "F.Fab")
		)
		(fp_line
			(start -0.67945 -0.305054)
			(end -0.12065 -0.305054)
			(stroke
				(width 0.1)
				(type default)
			)
			(layer "F.Fab")
		)
		(fp_line
			(start 0.67945 -0.3048)
			(end 0.67945 0.3048)
			(stroke
				(width 0.1)
				(type default)
			)
			(layer "F.Fab")
		)
		(fp_line
			(start 0.12065 -0.3048)
			(end 0.67945 -0.3048)
			(stroke
				(width 0.1)
				(type default)
			)
			(layer "F.Fab")
		)
		(fp_line
			(start 0.12065 -0.2794)
			(end 0.12065 -0.3048)
			(stroke
				(width 0.1)
				(type default)
			)
			(layer "F.Fab")
		)
		(fp_line
			(start -0.12065 -0.2794)
			(end 0.12065 -0.2794)
			(stroke
				(width 0.1)
				(type default)
			)
			(layer "F.Fab")
		)
		(fp_line
			(start 0.120396 0.2794)
			(end -0.12065 0.2794)
			(stroke
				(width 0.1)
				(type default)
			)
			(layer "F.Fab")
		)
		(fp_line
			(start -0.12065 0.2794)
			(end -0.12065 0.3048)
			(stroke
				(width 0.1)
				(type default)
			)
			(layer "F.Fab")
		)
		(fp_line
			(start 0.67945 0.3048)
			(end 0.120396 0.3048)
			(stroke
				(width 0.1)
				(type default)
			)
			(layer "F.Fab")
		)
		(fp_line
			(start 0.120396 0.3048)
			(end 0.120396 0.2794)
			(stroke
				(width 0.1)
				(type default)
			)
			(layer "F.Fab")
		)
		(fp_line
			(start -0.12065 0.3048)
			(end -0.67945 0.3048)
			(stroke
				(width 0.1)
				(type default)
			)
			(layer "F.Fab")
		)
		(fp_line
			(start -0.67945 0.3048)
			(end -0.67945 -0.305054)
			(stroke
				(width 0.1)
				(type default)
			)
			(layer "F.Fab")
		)
		(pad "1" smd circle
			(at -0.40005 0 90)
			(size 0 0)
			(layers "F.Cu" "F.Mask" "F.Paste")
			(net "SPI_BMC_BIOS_ROM_IO2")
		)
		(pad "2" smd circle
			(at 0.40005 0 90)
			(size 0 0)
			(layers "F.Cu" "F.Mask" "F.Paste")
			(net "SPI_BMC_BIOS_ROM_R_IO2")
		)
	)
	(footprint ""
		(layer "F.Cu")
		(at 71.013828 -62.776608 -90)
		(property "Reference" "C61"
			(at 0 0 270)
			(layer "F.SilkS")
			(hide yes)
			(effects
				(font
					(size 1.27 1.27)
				)
			)
		)
		(property "Value" ""
			(at 0 0 270)
			(layer "F.Fab")
			(effects
				(font
					(size 1.27 1.27)
				)
			)
		)
		(duplicate_pad_numbers_are_jumpers no)
		(fp_line
			(start -0.7874 0.4064)
			(end -0.7874 -0.4064)
			(stroke
				(width 0.1524)
				(type default)
			)
			(layer "F.SilkS")
		)
		(fp_line
			(start 0.7874 0.4064)
			(end -0.7874 0.4064)
			(stroke
				(width 0.1524)
				(type default)
			)
			(layer "F.SilkS")
		)
		(fp_line
			(start -0.7874 -0.4064)
			(end 0.7874 -0.4064)
			(stroke
				(width 0.1524)
				(type default)
			)
			(layer "F.SilkS")
		)
		(fp_line
			(start 0.7874 -0.4064)
			(end 0.7874 0.4064)
			(stroke
				(width 0.1524)
				(type default)
			)
			(layer "F.SilkS")
		)
		(fp_line
			(start -0.67945 0.3048)
			(end -0.67945 -0.305054)
			(stroke
				(width 0.1)
				(type default)
			)
			(layer "F.Fab")
		)
		(fp_line
			(start -0.12065 0.3048)
			(end -0.67945 0.3048)
			(stroke
				(width 0.1)
				(type default)
			)
			(layer "F.Fab")
		)
		(fp_line
			(start 0.120396 0.3048)
			(end 0.120396 0.2794)
			(stroke
				(width 0.1)
				(type default)
			)
			(layer "F.Fab")
		)
		(fp_line
			(start 0.67945 0.3048)
			(end 0.120396 0.3048)
			(stroke
				(width 0.1)
				(type default)
			)
			(layer "F.Fab")
		)
		(fp_line
			(start -0.12065 0.2794)
			(end -0.12065 0.3048)
			(stroke
				(width 0.1)
				(type default)
			)
			(layer "F.Fab")
		)
		(fp_line
			(start 0.120396 0.2794)
			(end -0.12065 0.2794)
			(stroke
				(width 0.1)
				(type default)
			)
			(layer "F.Fab")
		)
		(fp_line
			(start -0.12065 -0.2794)
			(end 0.12065 -0.2794)
			(stroke
				(width 0.1)
				(type default)
			)
			(layer "F.Fab")
		)
		(fp_line
			(start 0.12065 -0.2794)
			(end 0.12065 -0.3048)
			(stroke
				(width 0.1)
				(type default)
			)
			(layer "F.Fab")
		)
		(fp_line
			(start 0.12065 -0.3048)
			(end 0.67945 -0.3048)
			(stroke
				(width 0.1)
				(type default)
			)
			(layer "F.Fab")
		)
		(fp_line
			(start 0.67945 -0.3048)
			(end 0.67945 0.3048)
			(stroke
				(width 0.1)
				(type default)
			)
			(layer "F.Fab")
		)
		(fp_line
			(start -0.67945 -0.305054)
			(end -0.12065 -0.305054)
			(stroke
				(width 0.1)
				(type default)
			)
			(layer "F.Fab")
		)
		(fp_line
			(start -0.12065 -0.305054)
			(end -0.12065 -0.2794)
			(stroke
				(width 0.1)
				(type default)
			)
			(layer "F.Fab")
		)
		(pad "1" smd circle
			(at -0.40005 0 270)
			(size 0 0)
			(layers "F.Cu" "F.Mask" "F.Paste")
			(net "P1V8_STBY_PE_VCC18A")
		)
		(pad "2" smd circle
			(at 0.40005 0 270)
			(size 0 0)
			(layers "F.Cu" "F.Mask" "F.Paste")
			(net "GND")
		)
	)
	(footprint ""
		(layer "F.Cu")
		(at 36.9824 -60.1726 -90)
		(property "Reference" "R565"
			(at 0 0 270)
			(layer "F.SilkS")
			(hide yes)
			(effects
				(font
					(size 1.27 1.27)
				)
			)
		)
		(property "Value" ""
			(at 0 0 270)
			(layer "F.Fab")
			(effects
				(font
					(size 1.27 1.27)
				)
			)
		)
		(duplicate_pad_numbers_are_jumpers no)
		(fp_line
			(start -0.7874 0.4064)
			(end -0.7874 -0.4064)
			(stroke
				(width 0.1524)
				(type default)
			)
			(layer "F.SilkS")
		)
		(fp_line
			(start 0.7874 0.4064)
			(end -0.7874 0.4064)
			(stroke
				(width 0.1524)
				(type default)
			)
			(layer "F.SilkS")
		)
		(fp_line
			(start -0.7874 -0.4064)
			(end 0.7874 -0.4064)
			(stroke
				(width 0.1524)
				(type default)
			)
			(layer "F.SilkS")
		)
		(fp_line
			(start 0.7874 -0.4064)
			(end 0.7874 0.4064)
			(stroke
				(width 0.1524)
				(type default)
			)
			(layer "F.SilkS")
		)
		(fp_line
			(start -0.67945 0.3048)
			(end -0.67945 -0.305054)
			(stroke
				(width 0.1)
				(type default)
			)
			(layer "F.Fab")
		)
		(fp_line
			(start -0.12065 0.3048)
			(end -0.67945 0.3048)
			(stroke
				(width 0.1)
				(type default)
			)
			(layer "F.Fab")
		)
		(fp_line
			(start 0.120396 0.3048)
			(end 0.120396 0.2794)
			(stroke
				(width 0.1)
				(type default)
			)
			(layer "F.Fab")
		)
		(fp_line
			(start 0.67945 0.3048)
			(end 0.120396 0.3048)
			(stroke
				(width 0.1)
				(type default)
			)
			(layer "F.Fab")
		)
		(fp_line
			(start -0.12065 0.2794)
			(end -0.12065 0.3048)
			(stroke
				(width 0.1)
				(type default)
			)
			(layer "F.Fab")
		)
		(fp_line
			(start 0.120396 0.2794)
			(end -0.12065 0.2794)
			(stroke
				(width 0.1)
				(type default)
			)
			(layer "F.Fab")
		)
		(fp_line
			(start -0.12065 -0.2794)
			(end 0.12065 -0.2794)
			(stroke
				(width 0.1)
				(type default)
			)
			(layer "F.Fab")
		)
		(fp_line
			(start 0.12065 -0.2794)
			(end 0.12065 -0.3048)
			(stroke
				(width 0.1)
				(type default)
			)
			(layer "F.Fab")
		)
		(fp_line
			(start 0.12065 -0.3048)
			(end 0.67945 -0.3048)
			(stroke
				(width 0.1)
				(type default)
			)
			(layer "F.Fab")
		)
		(fp_line
			(start 0.67945 -0.3048)
			(end 0.67945 0.3048)
			(stroke
				(width 0.1)
				(type default)
			)
			(layer "F.Fab")
		)
		(fp_line
			(start -0.67945 -0.305054)
			(end -0.12065 -0.305054)
			(stroke
				(width 0.1)
				(type default)
			)
			(layer "F.Fab")
		)
		(fp_line
			(start -0.12065 -0.305054)
			(end -0.12065 -0.2794)
			(stroke
				(width 0.1)
				(type default)
			)
			(layer "F.Fab")
		)
		(pad "1" smd circle
			(at -0.40005 0 270)
			(size 0 0)
			(layers "F.Cu" "F.Mask" "F.Paste")
			(net "ID_RST_BTN_BMC_R_N")
		)
		(pad "2" smd circle
			(at 0.40005 0 270)
			(size 0 0)
			(layers "F.Cu" "F.Mask" "F.Paste")
			(net "ID_RST_BTN_BMC_N")
		)
	)
	(footprint ""
		(layer "F.Cu")
		(at 32.69488 -57.45226 -90)
		(property "Reference" "R875"
			(at 0 0 270)
			(layer "F.SilkS")
			(hide yes)
			(effects
				(font
					(size 1.27 1.27)
				)
			)
		)
		(property "Value" ""
			(at 0 0 270)
			(layer "F.Fab")
			(effects
				(font
					(size 1.27 1.27)
				)
			)
		)
		(duplicate_pad_numbers_are_jumpers no)
		(fp_line
			(start -0.7874 0.4064)
			(end -0.7874 -0.4064)
			(stroke
				(width 0.1524)
				(type default)
			)
			(layer "F.SilkS")
		)
		(fp_line
			(start 0.7874 0.4064)
			(end -0.7874 0.4064)
			(stroke
				(width 0.1524)
				(type default)
			)
			(layer "F.SilkS")
		)
		(fp_line
			(start -0.7874 -0.4064)
			(end 0.7874 -0.4064)
			(stroke
				(width 0.1524)
				(type default)
			)
			(layer "F.SilkS")
		)
		(fp_line
			(start 0.7874 -0.4064)
			(end 0.7874 0.4064)
			(stroke
				(width 0.1524)
				(type default)
			)
			(layer "F.SilkS")
		)
		(fp_line
			(start -0.67945 0.3048)
			(end -0.67945 -0.305054)
			(stroke
				(width 0.1)
				(type default)
			)
			(layer "F.Fab")
		)
		(fp_line
			(start -0.12065 0.3048)
			(end -0.67945 0.3048)
			(stroke
				(width 0.1)
				(type default)
			)
			(layer "F.Fab")
		)
		(fp_line
			(start 0.120396 0.3048)
			(end 0.120396 0.2794)
			(stroke
				(width 0.1)
				(type default)
			)
			(layer "F.Fab")
		)
		(fp_line
			(start 0.67945 0.3048)
			(end 0.120396 0.3048)
			(stroke
				(width 0.1)
				(type default)
			)
			(layer "F.Fab")
		)
		(fp_line
			(start -0.12065 0.2794)
			(end -0.12065 0.3048)
			(stroke
				(width 0.1)
				(type default)
			)
			(layer "F.Fab")
		)
		(fp_line
			(start 0.120396 0.2794)
			(end -0.12065 0.2794)
			(stroke
				(width 0.1)
				(type default)
			)
			(layer "F.Fab")
		)
		(fp_line
			(start -0.12065 -0.2794)
			(end 0.12065 -0.2794)
			(stroke
				(width 0.1)
				(type default)
			)
			(layer "F.Fab")
		)
		(fp_line
			(start 0.12065 -0.2794)
			(end 0.12065 -0.3048)
			(stroke
				(width 0.1)
				(type default)
			)
			(layer "F.Fab")
		)
		(fp_line
			(start 0.12065 -0.3048)
			(end 0.67945 -0.3048)
			(stroke
				(width 0.1)
				(type default)
			)
			(layer "F.Fab")
		)
		(fp_line
			(start 0.67945 -0.3048)
			(end 0.67945 0.3048)
			(stroke
				(width 0.1)
				(type default)
			)
			(layer "F.Fab")
		)
		(fp_line
			(start -0.67945 -0.305054)
			(end -0.12065 -0.305054)
			(stroke
				(width 0.1)
				(type default)
			)
			(layer "F.Fab")
		)
		(fp_line
			(start -0.12065 -0.305054)
			(end -0.12065 -0.2794)
			(stroke
				(width 0.1)
				(type default)
			)
			(layer "F.Fab")
		)
		(pad "1" smd circle
			(at -0.40005 0 270)
			(size 0 0)
			(layers "F.Cu" "F.Mask" "F.Paste")
			(net "PWRGD_P2V5_AUX_R3")
		)
		(pad "2" smd circle
			(at 0.40005 0 270)
			(size 0 0)
			(layers "F.Cu" "F.Mask" "F.Paste")
			(net "EN_P1V8_R")
		)
	)
	(footprint ""
		(layer "F.Cu")
		(at 69.265292 -35.261296 90)
		(property "Reference" "C119"
			(at 0 0 90)
			(layer "F.SilkS")
			(hide yes)
			(effects
				(font
					(size 1.27 1.27)
				)
			)
		)
		(property "Value" ""
			(at 0 0 90)
			(layer "F.Fab")
			(effects
				(font
					(size 1.27 1.27)
				)
			)
		)
		(duplicate_pad_numbers_are_jumpers no)
		(fp_line
			(start 0.7874 -0.4064)
			(end 0.7874 0.4064)
			(stroke
				(width 0.1524)
				(type default)
			)
			(layer "F.SilkS")
		)
		(fp_line
			(start -0.7874 -0.4064)
			(end 0.7874 -0.4064)
			(stroke
				(width 0.1524)
				(type default)
			)
			(layer "F.SilkS")
		)
		(fp_line
			(start 0.7874 0.4064)
			(end -0.7874 0.4064)
			(stroke
				(width 0.1524)
				(type default)
			)
			(layer "F.SilkS")
		)
		(fp_line
			(start -0.7874 0.4064)
			(end -0.7874 -0.4064)
			(stroke
				(width 0.1524)
				(type default)
			)
			(layer "F.SilkS")
		)
		(fp_line
			(start -0.12065 -0.305054)
			(end -0.12065 -0.2794)
			(stroke
				(width 0.1)
				(type default)
			)
			(layer "F.Fab")
		)
		(fp_line
			(start -0.67945 -0.305054)
			(end -0.12065 -0.305054)
			(stroke
				(width 0.1)
				(type default)
			)
			(layer "F.Fab")
		)
		(fp_line
			(start 0.67945 -0.3048)
			(end 0.67945 0.3048)
			(stroke
				(width 0.1)
				(type default)
			)
			(layer "F.Fab")
		)
		(fp_line
			(start 0.12065 -0.3048)
			(end 0.67945 -0.3048)
			(stroke
				(width 0.1)
				(type default)
			)
			(layer "F.Fab")
		)
		(fp_line
			(start 0.12065 -0.2794)
			(end 0.12065 -0.3048)
			(stroke
				(width 0.1)
				(type default)
			)
			(layer "F.Fab")
		)
		(fp_line
			(start -0.12065 -0.2794)
			(end 0.12065 -0.2794)
			(stroke
				(width 0.1)
				(type default)
			)
			(layer "F.Fab")
		)
		(fp_line
			(start 0.120396 0.2794)
			(end -0.12065 0.2794)
			(stroke
				(width 0.1)
				(type default)
			)
			(layer "F.Fab")
		)
		(fp_line
			(start -0.12065 0.2794)
			(end -0.12065 0.3048)
			(stroke
				(width 0.1)
				(type default)
			)
			(layer "F.Fab")
		)
		(fp_line
			(start 0.67945 0.3048)
			(end 0.120396 0.3048)
			(stroke
				(width 0.1)
				(type default)
			)
			(layer "F.Fab")
		)
		(fp_line
			(start 0.120396 0.3048)
			(end 0.120396 0.2794)
			(stroke
				(width 0.1)
				(type default)
			)
			(layer "F.Fab")
		)
		(fp_line
			(start -0.12065 0.3048)
			(end -0.67945 0.3048)
			(stroke
				(width 0.1)
				(type default)
			)
			(layer "F.Fab")
		)
		(fp_line
			(start -0.67945 0.3048)
			(end -0.67945 -0.305054)
			(stroke
				(width 0.1)
				(type default)
			)
			(layer "F.Fab")
		)
		(pad "1" smd circle
			(at -0.40005 0 90)
			(size 0 0)
			(layers "F.Cu" "F.Mask" "F.Paste")
			(net "P1V8_AUX")
		)
		(pad "2" smd circle
			(at 0.40005 0 90)
			(size 0 0)
			(layers "F.Cu" "F.Mask" "F.Paste")
			(net "GND")
		)
	)
	(footprint ""
		(layer "F.Cu")
		(at 5.13207 -64.550798 -90)
		(property "Reference" "PC221"
			(at 0 0 270)
			(layer "F.SilkS")
			(hide yes)
			(effects
				(font
					(size 1.27 1.27)
				)
			)
		)
		(property "Value" ""
			(at 0 0 270)
			(layer "F.Fab")
			(effects
				(font
					(size 1.27 1.27)
				)
			)
		)
		(duplicate_pad_numbers_are_jumpers no)
		(fp_line
			(start -0.7874 0.4064)
			(end -0.7874 -0.4064)
			(stroke
				(width 0.1524)
				(type default)
			)
			(layer "F.SilkS")
		)
		(fp_line
			(start 0.7874 0.4064)
			(end -0.7874 0.4064)
			(stroke
				(width 0.1524)
				(type default)
			)
			(layer "F.SilkS")
		)
		(fp_line
			(start -0.7874 -0.4064)
			(end 0.7874 -0.4064)
			(stroke
				(width 0.1524)
				(type default)
			)
			(layer "F.SilkS")
		)
		(fp_line
			(start 0.7874 -0.4064)
			(end 0.7874 0.4064)
			(stroke
				(width 0.1524)
				(type default)
			)
			(layer "F.SilkS")
		)
		(fp_line
			(start -0.67945 0.3048)
			(end -0.67945 -0.305054)
			(stroke
				(width 0.1)
				(type default)
			)
			(layer "F.Fab")
		)
		(fp_line
			(start -0.12065 0.3048)
			(end -0.67945 0.3048)
			(stroke
				(width 0.1)
				(type default)
			)
			(layer "F.Fab")
		)
		(fp_line
			(start 0.120396 0.3048)
			(end 0.120396 0.2794)
			(stroke
				(width 0.1)
				(type default)
			)
			(layer "F.Fab")
		)
		(fp_line
			(start 0.67945 0.3048)
			(end 0.120396 0.3048)
			(stroke
				(width 0.1)
				(type default)
			)
			(layer "F.Fab")
		)
		(fp_line
			(start -0.12065 0.2794)
			(end -0.12065 0.3048)
			(stroke
				(width 0.1)
				(type default)
			)
			(layer "F.Fab")
		)
		(fp_line
			(start 0.120396 0.2794)
			(end -0.12065 0.2794)
			(stroke
				(width 0.1)
				(type default)
			)
			(layer "F.Fab")
		)
		(fp_line
			(start -0.12065 -0.2794)
			(end 0.12065 -0.2794)
			(stroke
				(width 0.1)
				(type default)
			)
			(layer "F.Fab")
		)
		(fp_line
			(start 0.12065 -0.2794)
			(end 0.12065 -0.3048)
			(stroke
				(width 0.1)
				(type default)
			)
			(layer "F.Fab")
		)
		(fp_line
			(start 0.12065 -0.3048)
			(end 0.67945 -0.3048)
			(stroke
				(width 0.1)
				(type default)
			)
			(layer "F.Fab")
		)
		(fp_line
			(start 0.67945 -0.3048)
			(end 0.67945 0.3048)
			(stroke
				(width 0.1)
				(type default)
			)
			(layer "F.Fab")
		)
		(fp_line
			(start -0.67945 -0.305054)
			(end -0.12065 -0.305054)
			(stroke
				(width 0.1)
				(type default)
			)
			(layer "F.Fab")
		)
		(fp_line
			(start -0.12065 -0.305054)
			(end -0.12065 -0.2794)
			(stroke
				(width 0.1)
				(type default)
			)
			(layer "F.Fab")
		)
		(pad "1" smd circle
			(at -0.40005 0 270)
			(size 0 0)
			(layers "F.Cu" "F.Mask" "F.Paste")
			(net "P3V3_AUX_VCC")
		)
		(pad "2" smd circle
			(at 0.40005 0 270)
			(size 0 0)
			(layers "F.Cu" "F.Mask" "F.Paste")
			(net "GND")
		)
	)
)
